(kicad_pcb
	(version 20221018)
	(generator pcbnew)
	(general
    (thickness 1.6)
  )
	(paper "A4")
	(title_block
    (title "NUC Computer Cluster Power Breakout HW")
    (date "2023-10-18")
    (rev "1.4.3")
    (company "Antmicro Ltd.")
		(comment 9 "footprints 10-13 of 234")
	)
	(layers
    (0 "F.Cu" mixed)
    (1 "In1.Cu" power)
    (2 "In2.Cu" mixed)
    (31 "B.Cu" power)
    (32 "B.Adhes" user "B.Adhesive")
    (33 "F.Adhes" user "F.Adhesive")
    (34 "B.Paste" user)
    (35 "F.Paste" user)
    (36 "B.SilkS" user "B.Silkscreen")
    (37 "F.SilkS" user "F.Silkscreen")
    (38 "B.Mask" user)
    (39 "F.Mask" user)
    (40 "Dwgs.User" user "User.Drawings")
    (41 "Cmts.User" user "User.Comments")
    (42 "Eco1.User" user "User.Eco1")
    (43 "Eco2.User" user "User.Eco2")
    (44 "Edge.Cuts" user)
    (45 "Margin" user)
    (46 "B.CrtYd" user "B.Courtyard")
    (47 "F.CrtYd" user "F.Courtyard")
    (48 "B.Fab" user)
    (49 "F.Fab" user)
  )
	(footprint "antmicro-footprints:Conn_JST_SH_1x4_BM04B-SRSS-TB-LF-SN" (layer "F.Cu")
    (at 185.625 94.95)
    (property "Author" "Antmicro")
    (property "DNP" "DNP")
    (property "License" "Apache-2.0")
    (property "MPN" "BM04B-SRSS-TB(LF)(SN) ")
    (property "Manufacturer" "JST Automotive Connectors")
    (property "Sheetfile" "d1600e-psu-breakout-board.kicad_sch")
    (property "Sheetname" "")
    (property "dnp" "")
    (property "exclude_from_bom" "")
    (property "ki_description" "Pin Header, Top Entry, Wire-to-Board, 1 mm, 1 Rows, 4 Contacts, Surface Mount, SR")
    (property "ki_keywords" "VERTICAL, SMT, WIRE-BOARD, CONNECTOR")
    (attr smd exclude_from_bom)
    (fp_text reference "J2" (at 3.025 0.6 90) (layer "F.SilkS")
        (effects (font (size 0.7 0.7) (thickness 0.15)) (justify left bottom))
    )
    (fp_text value "JST_SH_1x4_BM04B-SRSS-TB-LF-SN" (at -3.25 5) (layer "F.Fab")
        (effects (font (size 0.7 0.7) (thickness 0.15)) (justify left bottom))
    )
    (fp_text user "License: Apache-2.0" (at -3.25 9.4) (layer "F.Fab") hide
        (effects (font (size 0.7 0.7) (thickness 0.15)) (justify left bottom))
    )
    (fp_text user "${REFERENCE}" (at -3.25 8.2) (layer "F.Fab") hide
        (effects (font (size 0.7 0.7) (thickness 0.15)) (justify left bottom))
    )
    (fp_text user "Author: Antmicro" (at -3.25 7) (layer "F.Fab") hide
        (effects (font (size 0.7 0.7) (thickness 0.15)) (justify left bottom))
    )
    (fp_line (start -1.125 -2.999) (end -1.125 -2.201)
      (stroke (width 0.15) (type solid)) (layer "F.SilkS"))
    (fp_line (start -1.125 2.999) (end -1.125 2.201)
      (stroke (width 0.15) (type solid)) (layer "F.SilkS"))
    (fp_line (start -0.251 -2.999) (end -1.125 -2.999)
      (stroke (width 0.15) (type solid)) (layer "F.SilkS"))
    (fp_line (start -0.251 2.999) (end -1.125 2.999)
      (stroke (width 0.15) (type solid)) (layer "F.SilkS"))
    (fp_line (start 1.774 -1.7) (end 1.774 1.702)
      (stroke (width 0.15) (type solid)) (layer "F.SilkS"))
    (fp_circle (center -1.6 -2.1) (end -1.55 -2.1)
      (stroke (width 0.15) (type solid)) (fill solid) (layer "F.SilkS"))
    (fp_rect (start -2.05 -3.95) (end 2.05 3.95)
      (stroke (width 0.05) (type solid)) (fill none) (layer "F.CrtYd"))
    (fp_rect (start -1.8 -3) (end 1.8 3)
      (stroke (width 0.15) (type solid)) (fill none) (layer "F.Fab"))
    (pad "1" smd roundrect (at -1.45 -1.5 270) (size 0.6 1.55) (layers "F.Cu" "F.Paste" "F.Mask") (roundrect_rratio 0.25)
      (net 19 "Net-(J2-Pad1)") (pintype "passive"))
    (pad "2" smd roundrect (at -1.45 -0.5 270) (size 0.6 1.55) (layers "F.Cu" "F.Paste" "F.Mask") (roundrect_rratio 0.25)
      (net 18 "SDA") (pintype "passive"))
    (pad "3" smd roundrect (at -1.45 0.5 270) (size 0.6 1.55) (layers "F.Cu" "F.Paste" "F.Mask") (roundrect_rratio 0.25)
      (net 17 "SCL") (pintype "passive"))
    (pad "4" smd roundrect (at -1.45 1.5 270) (size 0.6 1.55) (layers "F.Cu" "F.Paste" "F.Mask") (roundrect_rratio 0.25)
      (net 4 "GND") (pintype "passive"))
    (pad "MP" smd roundrect (at 1.075 -2.8 270) (size 1.2 1.8) (layers "F.Cu" "F.Paste" "F.Mask") (roundrect_rratio 0.25)
      (net 89 "unconnected-(J2-PadMP)") (pintype "passive+no_connect"))
    (pad "MP" smd roundrect (at 1.075 2.8 270) (size 1.2 1.8) (layers "F.Cu" "F.Paste" "F.Mask") (roundrect_rratio 0.25)
      (net 89 "unconnected-(J2-PadMP)") (pintype "passive+no_connect"))
  )
	(footprint "antmicro-footprints:L_WE-LHMI-5030" (layer "F.Cu")
    (at 93.25 90.1 90)
    (property "Author" "Antmicro")
    (property "IMax" "4.1A")
    (property "ISat" "5.45A")
    (property "License" "Apache-2.0")
    (property "MPN" "74437336033")
    (property "Manufacturer" "Würth Elektronik")
    (property "Sheetfile" "daughterboard-supply.kicad_sch")
    (property "Sheetname" "daughterboard-supply")
    (property "Size" "5.2x5.2")
    (property "Val" "3u3/4.1A")
    (property "ki_description" "Power Inductor (SMT), 3.3 µH, 4.1 A, Shielded, 8.4 A, WE-LHMI")
    (property "ki_keywords" "SMT, INDUCTOR, PASSIVE")
    (attr smd)
    (fp_text reference "L2" (at 3.25 -2.7) (layer "F.SilkS")
        (effects (font (size 0.7 0.7) (thickness 0.15)) (justify left bottom))
    )
    (fp_text value "L_3u3_4.1A_WE-LHMI-5030" (at 0 3.9 270) (layer "F.Fab")
        (effects (font (size 0.7 0.7) (thickness 0.15)) (justify left bottom))
    )
    (fp_text user "Author: Antmicro" (at -3.5 5.9 90) (layer "F.Fab") hide
        (effects (font (size 0.7 0.7) (thickness 0.15)) (justify left bottom))
    )
    (fp_text user "${REFERENCE}" (at -3.5 7.1 90) (layer "F.Fab") hide
        (effects (font (size 0.7 0.7) (thickness 0.15)) (justify left bottom))
    )
    (fp_text user "License: Apache-2.0" (at -3.5 8.3 90) (layer "F.Fab") hide
        (effects (font (size 0.7 0.7) (thickness 0.15)) (justify left bottom))
    )
    (fp_line (start -2.725 -1.6125) (end -2.725 -1.125)
      (stroke (width 0.15) (type solid)) (layer "F.SilkS"))
    (fp_line (start -2.725 1.6125) (end -2.725 1.125)
      (stroke (width 0.15) (type solid)) (layer "F.SilkS"))
    (fp_line (start -1.6 -2.725) (end 1.6 -2.725)
      (stroke (width 0.15) (type solid)) (layer "F.SilkS"))
    (fp_line (start 1.6 2.725) (end -1.6 2.725)
      (stroke (width 0.15) (type solid)) (layer "F.SilkS"))
    (fp_line (start 2.725 -1.6125) (end 2.725 -1.125)
      (stroke (width 0.15) (type solid)) (layer "F.SilkS"))
    (fp_line (start 2.725 1.6125) (end 2.725 1.125)
      (stroke (width 0.15) (type solid)) (layer "F.SilkS"))
    (fp_arc (start -2.725 -1.6125) (mid -2.392906 -2.401745) (end -1.6 -2.725)
      (stroke (width 0.15) (type solid)) (layer "F.SilkS"))
    (fp_arc (start -1.6 2.725) (mid -2.392906 2.401745) (end -2.725 1.6125)
      (stroke (width 0.15) (type solid)) (layer "F.SilkS"))
    (fp_arc (start 1.6 -2.725) (mid 2.392906 -2.401745) (end 2.725 -1.6125)
      (stroke (width 0.15) (type solid)) (layer "F.SilkS"))
    (fp_arc (start 2.725 1.6125) (mid 2.392906 2.401745) (end 1.6 2.725)
      (stroke (width 0.15) (type solid)) (layer "F.SilkS"))
    (fp_line (start -3.5 1.15) (end -3.5 -1.15)
      (stroke (width 0.05) (type solid)) (layer "F.CrtYd"))
    (fp_line (start -3.1 -2.85) (end 3.1 -2.85)
      (stroke (width 0.05) (type solid)) (layer "F.CrtYd"))
    (fp_line (start -3.1 -1.15) (end -3.5 -1.15)
      (stroke (width 0.05) (type solid)) (layer "F.CrtYd"))
    (fp_line (start -3.1 -1.15) (end -3.1 -2.85)
      (stroke (width 0.05) (type solid)) (layer "F.CrtYd"))
    (fp_line (start -3.1 1.15) (end -3.5 1.15)
      (stroke (width 0.05) (type solid)) (layer "F.CrtYd"))
    (fp_line (start -3.1 2.85) (end -3.1 1.15)
      (stroke (width 0.05) (type solid)) (layer "F.CrtYd"))
    (fp_line (start 3.1 -2.85) (end 3.1 -1.15)
      (stroke (width 0.05) (type solid)) (layer "F.CrtYd"))
    (fp_line (start 3.1 -1.15) (end 3.5 -1.15)
      (stroke (width 0.05) (type solid)) (layer "F.CrtYd"))
    (fp_line (start 3.1 1.15) (end 3.1 2.85)
      (stroke (width 0.05) (type solid)) (layer "F.CrtYd"))
    (fp_line (start 3.1 1.15) (end 3.5 1.15)
      (stroke (width 0.05) (type solid)) (layer "F.CrtYd"))
    (fp_line (start 3.1 2.85) (end -3.1 2.85)
      (stroke (width 0.05) (type solid)) (layer "F.CrtYd"))
    (fp_line (start 3.5 -1.15) (end 3.5 1.15)
      (stroke (width 0.05) (type solid)) (layer "F.CrtYd"))
    (fp_rect (start -2.85 -2.6) (end 2.85 2.6)
      (stroke (width 0.15) (type solid)) (fill none) (layer "F.Fab"))
    (pad "1" smd roundrect (at -2.25 0 270) (size 2 1.8) (layers "F.Cu" "F.Paste" "F.Mask") (roundrect_rratio 0.1)
      (net 13 "Net-(U15-SW)") (pintype "passive"))
    (pad "2" smd roundrect (at 2.25 0 90) (size 2 1.8) (layers "F.Cu" "F.Paste" "F.Mask") (roundrect_rratio 0.1)
      (net 2 "VCC5V0") (pintype "passive"))
  )
	(footprint "antmicro-footprints:SOT-23-3" (layer "F.Cu")
    (at 112.5 86.8)
    (property "Author" "Antmicro")
    (property "License" "Apache-2.0")
    (property "MPN" "2N7002")
    (property "Manufacturer" "ON Semiconductor")
    (property "Sheetfile" "power-switch.kicad_sch")
    (property "Sheetname" "Power switch 1")
    (property "ki_description" "Power MOSFET, N Channel, 60 V, 115 mA, 1.2 ohm, SOT-23, Surface Mount")
    (property "ki_keywords" "SMT, TRANSISTOR, SEMICONDUCTOR, NMOS")
    (attr smd)
    (fp_text reference "Q6" (at 0.8 2.4) (layer "F.SilkS")
        (effects (font (size 0.7 0.7) (thickness 0.15)) (justify left bottom))
    )
    (fp_text value "2N7002_SOT-23-3" (at -1.9 2.7) (layer "F.Fab")
        (effects (font (size 0.7 0.7) (thickness 0.15)) (justify left bottom))
    )
    (fp_text user "${REFERENCE}" (at -1.837 4) (layer "F.Fab") hide
        (effects (font (size 0.7 0.7) (thickness 0.15)) (justify left bottom))
    )
    (fp_text user "License: Apache-2.0" (at -1.8 6.8) (layer "F.Fab") hide
        (effects (font (size 0.7 0.7) (thickness 0.15)) (justify left bottom))
    )
    (fp_text user "Author: Antmicro" (at -1.837 5.3) (layer "F.Fab") hide
        (effects (font (size 0.7 0.7) (thickness 0.15)) (justify left bottom))
    )
    (fp_line (start -1.45 -1.35) (end -0.85 -1.35)
      (stroke (width 0.15) (type solid)) (layer "F.SilkS"))
    (fp_line (start -0.85 -1.35) (end -0.7 -1.5)
      (stroke (width 0.15) (type solid)) (layer "F.SilkS"))
    (fp_line (start -0.7 1.5) (end -0.7 1.35)
      (stroke (width 0.15) (type solid)) (layer "F.SilkS"))
    (fp_line (start 0.7 -1.5) (end -0.7 -1.5)
      (stroke (width 0.15) (type solid)) (layer "F.SilkS"))
    (fp_line (start 0.7 -0.4) (end 0.7 -1.5)
      (stroke (width 0.15) (type solid)) (layer "F.SilkS"))
    (fp_line (start 0.7 0.4) (end 0.7 1.5)
      (stroke (width 0.15) (type solid)) (layer "F.SilkS"))
    (fp_line (start 0.7 1.5) (end -0.7 1.5)
      (stroke (width 0.15) (type solid)) (layer "F.SilkS"))
    (fp_line (start -1.75 -0.5) (end -1.75 -1.4)
      (stroke (width 0.05) (type solid)) (layer "F.CrtYd"))
    (fp_line (start -1.75 0.5) (end -0.85 0.5)
      (stroke (width 0.05) (type solid)) (layer "F.CrtYd"))
    (fp_line (start -1.75 1.4) (end -1.75 0.5)
      (stroke (width 0.05) (type solid)) (layer "F.CrtYd"))
    (fp_line (start -0.9 -1.6) (end -0.9 -1.4)
      (stroke (width 0.05) (type solid)) (layer "F.CrtYd"))
    (fp_line (start -0.9 -1.6) (end 0.825 -1.6)
      (stroke (width 0.05) (type solid)) (layer "F.CrtYd"))
    (fp_line (start -0.9 -1.4) (end -1.75 -1.4)
      (stroke (width 0.05) (type solid)) (layer "F.CrtYd"))
    (fp_line (start -0.85 -0.5) (end -1.75 -0.5)
      (stroke (width 0.05) (type solid)) (layer "F.CrtYd"))
    (fp_line (start -0.85 0.5) (end -0.85 -0.5)
      (stroke (width 0.05) (type solid)) (layer "F.CrtYd"))
    (fp_line (start -0.85 1.4) (end -1.75 1.4)
      (stroke (width 0.05) (type solid)) (layer "F.CrtYd"))
    (fp_line (start -0.85 1.65) (end -0.85 1.4)
      (stroke (width 0.05) (type solid)) (layer "F.CrtYd"))
    (fp_line (start 0.825 -1.6) (end 0.825 -0.45)
      (stroke (width 0.05) (type solid)) (layer "F.CrtYd"))
    (fp_line (start 0.825 -0.45) (end 1.75 -0.45)
      (stroke (width 0.05) (type solid)) (layer "F.CrtYd"))
    (fp_line (start 0.85 0.45) (end 0.85 1.65)
      (stroke (width 0.05) (type solid)) (layer "F.CrtYd"))
    (fp_line (start 0.85 1.65) (end -0.85 1.65)
      (stroke (width 0.05) (type solid)) (layer "F.CrtYd"))
    (fp_line (start 1.75 -0.45) (end 1.75 0.45)
      (stroke (width 0.05) (type solid)) (layer "F.CrtYd"))
    (fp_line (start 1.75 0.45) (end 0.85 0.45)
      (stroke (width 0.05) (type solid)) (layer "F.CrtYd"))
    (fp_line (start -0.712 -1.325) (end -0.712 1.523)
      (stroke (width 0.15) (type solid)) (layer "F.Fab"))
    (fp_line (start -0.712 1.519) (end 0.688 1.519)
      (stroke (width 0.15) (type solid)) (layer "F.Fab"))
    (fp_line (start -0.437 -1.526) (end -0.712 -1.325)
      (stroke (width 0.15) (type solid)) (layer "F.Fab"))
    (fp_line (start -0.437 -1.526) (end 0.688 -1.526)
      (stroke (width 0.15) (type solid)) (layer "F.Fab"))
    (fp_line (start 0.688 1.519) (end 0.688 -1.52)
      (stroke (width 0.15) (type solid)) (layer "F.Fab"))
    (pad "1" smd roundrect (at -1.1 -0.951) (size 1 0.6) (layers "F.Cu" "F.Paste" "F.Mask") (roundrect_rratio 0.15)
      (net 23 "/Power Cycling & Current Measurement/PC_1") (pinfunction "G") (pintype "passive"))
    (pad "2" smd roundrect (at -1.1 0.949) (size 1 0.6) (layers "F.Cu" "F.Paste" "F.Mask") (roundrect_rratio 0.15)
      (net 4 "GND") (pinfunction "S") (pintype "passive"))
    (pad "3" smd roundrect (at 1.1 -0.0005) (size 1 0.6) (layers "F.Cu" "F.Paste" "F.Mask") (roundrect_rratio 0.15)
      (net 83 "Net-(D15-A)") (pinfunction "D") (pintype "passive"))
  )
	(footprint "antmicro-footprints:SOT-23-3" (layer "F.Cu")
    (at 129.8 86.9)
    (property "Author" "Antmicro")
    (property "License" "Apache-2.0")
    (property "MPN" "2N7002")
    (property "Manufacturer" "ON Semiconductor")
    (property "Sheetfile" "power-switch.kicad_sch")
    (property "Sheetname" "Power switch 2")
    (property "ki_description" "Power MOSFET, N Channel, 60 V, 115 mA, 1.2 ohm, SOT-23, Surface Mount")
    (property "ki_keywords" "SMT, TRANSISTOR, SEMICONDUCTOR, NMOS")
    (attr smd)
    (fp_text reference "Q7" (at 0.55 2.5) (layer "F.SilkS")
        (effects (font (size 0.7 0.7) (thickness 0.15)) (justify left bottom))
    )
    (fp_text value "2N7002_SOT-23-3" (at -1.9 2.7) (layer "F.Fab")
        (effects (font (size 0.7 0.7) (thickness 0.15)) (justify left bottom))
    )
    (fp_text user "Author: Antmicro" (at -1.837 5.3) (layer "F.Fab") hide
        (effects (font (size 0.7 0.7) (thickness 0.15)) (justify left bottom))
    )
    (fp_text user "License: Apache-2.0" (at -1.8 6.8) (layer "F.Fab") hide
        (effects (font (size 0.7 0.7) (thickness 0.15)) (justify left bottom))
    )
    (fp_text user "${REFERENCE}" (at -1.837 4) (layer "F.Fab") hide
        (effects (font (size 0.7 0.7) (thickness 0.15)) (justify left bottom))
    )
    (fp_line (start -1.45 -1.35) (end -0.85 -1.35)
      (stroke (width 0.15) (type solid)) (layer "F.SilkS"))
    (fp_line (start -0.85 -1.35) (end -0.7 -1.5)
      (stroke (width 0.15) (type solid)) (layer "F.SilkS"))
    (fp_line (start -0.7 1.5) (end -0.7 1.35)
      (stroke (width 0.15) (type solid)) (layer "F.SilkS"))
    (fp_line (start 0.7 -1.5) (end -0.7 -1.5)
      (stroke (width 0.15) (type solid)) (layer "F.SilkS"))
    (fp_line (start 0.7 -0.4) (end 0.7 -1.5)
      (stroke (width 0.15) (type solid)) (layer "F.SilkS"))
    (fp_line (start 0.7 0.4) (end 0.7 1.5)
      (stroke (width 0.15) (type solid)) (layer "F.SilkS"))
    (fp_line (start 0.7 1.5) (end -0.7 1.5)
      (stroke (width 0.15) (type solid)) (layer "F.SilkS"))
    (fp_line (start -1.75 -0.5) (end -1.75 -1.4)
      (stroke (width 0.05) (type solid)) (layer "F.CrtYd"))
    (fp_line (start -1.75 0.5) (end -0.85 0.5)
      (stroke (width 0.05) (type solid)) (layer "F.CrtYd"))
    (fp_line (start -1.75 1.4) (end -1.75 0.5)
      (stroke (width 0.05) (type solid)) (layer "F.CrtYd"))
    (fp_line (start -0.9 -1.6) (end -0.9 -1.4)
      (stroke (width 0.05) (type solid)) (layer "F.CrtYd"))
    (fp_line (start -0.9 -1.6) (end 0.825 -1.6)
      (stroke (width 0.05) (type solid)) (layer "F.CrtYd"))
    (fp_line (start -0.9 -1.4) (end -1.75 -1.4)
      (stroke (width 0.05) (type solid)) (layer "F.CrtYd"))
    (fp_line (start -0.85 -0.5) (end -1.75 -0.5)
      (stroke (width 0.05) (type solid)) (layer "F.CrtYd"))
    (fp_line (start -0.85 0.5) (end -0.85 -0.5)
      (stroke (width 0.05) (type solid)) (layer "F.CrtYd"))
    (fp_line (start -0.85 1.4) (end -1.75 1.4)
      (stroke (width 0.05) (type solid)) (layer "F.CrtYd"))
    (fp_line (start -0.85 1.65) (end -0.85 1.4)
      (stroke (width 0.05) (type solid)) (layer "F.CrtYd"))
    (fp_line (start 0.825 -1.6) (end 0.825 -0.45)
      (stroke (width 0.05) (type solid)) (layer "F.CrtYd"))
    (fp_line (start 0.825 -0.45) (end 1.75 -0.45)
      (stroke (width 0.05) (type solid)) (layer "F.CrtYd"))
    (fp_line (start 0.85 0.45) (end 0.85 1.65)
      (stroke (width 0.05) (type solid)) (layer "F.CrtYd"))
    (fp_line (start 0.85 1.65) (end -0.85 1.65)
      (stroke (width 0.05) (type solid)) (layer "F.CrtYd"))
    (fp_line (start 1.75 -0.45) (end 1.75 0.45)
      (stroke (width 0.05) (type solid)) (layer "F.CrtYd"))
    (fp_line (start 1.75 0.45) (end 0.85 0.45)
      (stroke (width 0.05) (type solid)) (layer "F.CrtYd"))
    (fp_line (start -0.712 -1.325) (end -0.712 1.523)
      (stroke (width 0.15) (type solid)) (layer "F.Fab"))
    (fp_line (start -0.712 1.519) (end 0.688 1.519)
      (stroke (width 0.15) (type solid)) (layer "F.Fab"))
    (fp_line (start -0.437 -1.526) (end -0.712 -1.325)
      (stroke (width 0.15) (type solid)) (layer "F.Fab"))
    (fp_line (start -0.437 -1.526) (end 0.688 -1.526)
      (stroke (width 0.15) (type solid)) (layer "F.Fab"))
    (fp_line (start 0.688 1.519) (end 0.688 -1.52)
      (stroke (width 0.15) (type solid)) (layer "F.Fab"))
    (pad "1" smd roundrect (at -1.1 -0.951) (size 1 0.6) (layers "F.Cu" "F.Paste" "F.Mask") (roundrect_rratio 0.15)
      (net 24 "/Power Cycling & Current Measurement/PC_2") (pinfunction "G") (pintype "passive"))
    (pad "2" smd roundrect (at -1.1 0.949) (size 1 0.6) (layers "F.Cu" "F.Paste" "F.Mask") (roundrect_rratio 0.15)
      (net 4 "GND") (pinfunction "S") (pintype "passive"))
    (pad "3" smd roundrect (at 1.1 -0.0005) (size 1 0.6) (layers "F.Cu" "F.Paste" "F.Mask") (roundrect_rratio 0.15)
      (net 84 "Net-(D16-A)") (pinfunction "D") (pintype "passive"))
  )
)
